(kicad_pcb
	(version 20260206)
	(generator "pcbnew")
	(generator_version "10.0")
	(general
		(thickness 1.6)
		(legacy_teardrops no)
	)
	(paper "A4")
	(title_block
		(title "Wiwynn_Tioga_Pass_MB.brd")
		(comment 1 "Tioga Pass / footprints 4468-4473 of 4770")
	)
	(layers
		(0 "F.Cu" signal "TOP")
		(4 "In1.Cu" signal "L2GND")
		(6 "In2.Cu" signal "L3")
		(8 "In3.Cu" signal "L4GND")
		(10 "In4.Cu" signal "L5")
		(12 "In5.Cu" signal "L6GND")
		(14 "In6.Cu" signal "L7VCC")
		(16 "In7.Cu" signal "L8VCC")
		(18 "In8.Cu" signal "L9GND")
		(20 "In9.Cu" signal "L10")
		(22 "In10.Cu" signal "L11GND")
		(24 "In11.Cu" signal "L12")
		(26 "In12.Cu" signal "L13GND")
		(2 "B.Cu" signal "BOTTOM")
		(9 "F.Adhes" user "F.Adhesive")
		(11 "B.Adhes" user "B.Adhesive")
		(13 "F.Paste" user "Package Geometry/Pastemask Top")
		(15 "B.Paste" user "Package Geometry/Pastemask Bottom")
		(5 "F.SilkS" user "Ref Des/Silkscreen Top")
		(7 "B.SilkS" user "Ref Des/Silkscreen Bottom")
		(1 "F.Mask" user "Board Geometry/Soldermask Top")
		(3 "B.Mask" user "Board Geometry/Soldermask Bottom")
		(17 "Dwgs.User" user "User.Drawings")
		(19 "Cmts.User" user "User.Comments")
		(21 "Eco1.User" user "User.Eco1")
		(23 "Eco2.User" user "User.Eco2")
		(25 "Edge.Cuts" user "Board Geometry/Outline")
		(27 "Margin" user)
		(31 "F.CrtYd" user "Package Geometry/Place Bound Top")
		(29 "B.CrtYd" user "Package Geometry/Place Bound Bottom")
		(35 "F.Fab" user "Ref Des/Assembly Top")
		(33 "B.Fab" user "Ref Des/Assembly Bottom")
	)
	(footprint ""
		(layer "B.Cu")
		(at 45.611796 -95.596202 -90)
		(property "Reference" "C9N20"
			(at 0.626872 -3.791204 0)
			(unlocked yes)
			(layer "B.SilkS")
			(effects
				(font
					(size 0.7874 0.5842)
					(thickness 0.1524)
				)
				(justify mirror)
			)
		)
		(property "Value" ""
			(at 0 0 90)
			(layer "B.Fab")
			(effects
				(font
					(size 1.27 1.27)
				)
				(justify mirror)
			)
		)
		(duplicate_pad_numbers_are_jumpers no)
		(fp_line
			(start -2.286 7.366)
			(end -1.600708 7.366)
			(stroke
				(width 0.1524)
				(type default)
			)
			(layer "B.SilkS")
		)
		(fp_line
			(start -2.286 7.366)
			(end -2.286 1.63195)
			(stroke
				(width 0.1524)
				(type default)
			)
			(layer "B.SilkS")
		)
		(fp_line
			(start 2.286 7.366)
			(end 1.60147 7.366)
			(stroke
				(width 0.1524)
				(type default)
			)
			(layer "B.SilkS")
		)
		(fp_line
			(start 2.286 7.366)
			(end 2.286 1.632712)
			(stroke
				(width 0.1524)
				(type default)
			)
			(layer "B.SilkS")
		)
		(fp_line
			(start -2.504948 1.633728)
			(end -1.6002 1.633728)
			(stroke
				(width 0.1524)
				(type default)
			)
			(layer "B.SilkS")
		)
		(fp_line
			(start 2.563114 1.633728)
			(end 1.6002 1.633728)
			(stroke
				(width 0.1524)
				(type default)
			)
			(layer "B.SilkS")
		)
		(fp_line
			(start -2.504948 -1.616456)
			(end -2.504948 1.633728)
			(stroke
				(width 0.1524)
				(type default)
			)
			(layer "B.SilkS")
		)
		(fp_line
			(start -1.6002 -1.616456)
			(end -2.504948 -1.616456)
			(stroke
				(width 0.1524)
				(type default)
			)
			(layer "B.SilkS")
		)
		(fp_line
			(start 1.6002 -1.616456)
			(end 2.563114 -1.616456)
			(stroke
				(width 0.1524)
				(type default)
			)
			(layer "B.SilkS")
		)
		(fp_line
			(start 2.563114 -1.616456)
			(end 2.563114 1.633728)
			(stroke
				(width 0.1524)
				(type default)
			)
			(layer "B.SilkS")
		)
		(fp_rect
			(start 2.286 7.366)
			(end -2.286 -0.254)
			(stroke
				(width 0)
				(type default)
			)
			(fill no)
			(layer "B.CrtYd")
		)
		(fp_line
			(start -2.286 7.366)
			(end 2.286 7.366)
			(stroke
				(width 0.1)
				(type default)
			)
			(layer "B.Fab")
		)
		(fp_line
			(start 2.286 7.366)
			(end 2.286 -0.254)
			(stroke
				(width 0.1)
				(type default)
			)
			(layer "B.Fab")
		)
		(fp_line
			(start -2.286 -0.254)
			(end -2.286 7.366)
			(stroke
				(width 0.1)
				(type default)
			)
			(layer "B.Fab")
		)
		(fp_line
			(start 2.286 -0.254)
			(end -2.286 -0.254)
			(stroke
				(width 0.1)
				(type default)
			)
			(layer "B.Fab")
		)
		(pad "1" smd rect
			(at 0 0 90)
			(size 2.54 3.048)
			(layers "B.Cu" "B.Mask" "B.Paste")
			(net "PVSA_CPU1")
		)
		(pad "2" smd rect
			(at 0 7.112 90)
			(size 2.54 3.048)
			(layers "B.Cu" "B.Mask" "B.Paste")
			(net "GND")
		)
	)
	(footprint ""
		(layer "B.Cu")
		(at 13.360654 -122.704098 180)
		(property "Reference" "C10W2"
			(at 0.8382 -0.67818 180)
			(unlocked yes)
			(layer "B.SilkS")
			(effects
				(font
					(size 0.4064 0.254)
					(thickness 0.1524)
				)
				(justify left mirror)
			)
		)
		(property "Value" ""
			(at 0 0 0)
			(layer "B.Fab")
			(effects
				(font
					(size 1.27 1.27)
				)
				(justify mirror)
			)
		)
		(duplicate_pad_numbers_are_jumpers no)
		(fp_poly
			(pts
				(xy -0.3048 -0.1016) (xy -0.3048 0.9906) (xy 0.3048 0.9906) (xy 0.3048 -0.1016)
			)
			(stroke
				(width 0)
				(type default)
			)
			(fill no)
			(layer "B.CrtYd")
		)
		(fp_line
			(start 0.3048 0.9906)
			(end -0.3048 0.9906)
			(stroke
				(width 0.1)
				(type default)
			)
			(layer "B.Fab")
		)
		(fp_line
			(start 0.3048 -0.1016)
			(end 0.3048 0.9906)
			(stroke
				(width 0.1)
				(type default)
			)
			(layer "B.Fab")
		)
		(fp_line
			(start -0.3048 0.9906)
			(end -0.3048 -0.1016)
			(stroke
				(width 0.1)
				(type default)
			)
			(layer "B.Fab")
		)
		(fp_line
			(start -0.3048 -0.1016)
			(end 0.3048 -0.1016)
			(stroke
				(width 0.1)
				(type default)
			)
			(layer "B.Fab")
		)
		(pad "1" smd rect
			(at 0 0)
			(size 0.508 0.508)
			(layers "B.Cu" "B.Mask" "B.Paste")
			(net "P12V_PUMP")
		)
		(pad "2" smd rect
			(at 0 0.889)
			(size 0.508 0.508)
			(layers "B.Cu" "B.Mask" "B.Paste")
			(net "GND")
		)
		(zone
			(layer "B.Cu")
			(hatch none 0.5)
			(connect_pads
				(clearance 0)
			)
			(min_thickness 0.25)
			(keepout
				(tracks not_allowed)
				(vias allowed)
				(pads allowed)
				(copperpour not_allowed)
				(footprints allowed)
			)
			(placement
				(enabled no)
				(sheetname "")
			)
			(fill
				(thermal_gap 0.5)
				(thermal_bridge_width 0.5)
				(island_removal_mode 0)
			)
			(polygon
				(pts
					(xy 13.106654 -123.339098) (xy 13.614654 -123.339098) (xy 13.614654 -122.958098) (xy 13.106654 -122.958098)
				)
			)
		)
		(zone
			(layer "B.Cu")
			(hatch none 0.5)
			(connect_pads
				(clearance 0)
			)
			(min_thickness 0.25)
			(keepout
				(tracks allowed)
				(vias not_allowed)
				(pads allowed)
				(copperpour not_allowed)
				(footprints allowed)
			)
			(placement
				(enabled no)
				(sheetname "")
			)
			(fill
				(thermal_gap 0.5)
				(thermal_bridge_width 0.5)
				(island_removal_mode 0)
			)
			(polygon
				(pts
					(xy 13.106654 -122.958098) (xy 13.614654 -122.958098) (xy 13.614654 -123.339098) (xy 13.106654 -123.339098)
				)
			)
		)
	)
	(footprint ""
		(layer "B.Cu")
		(at 485.25938 -60.822332 90)
		(property "Reference" "C30W1"
			(at 0.8382 -0.67818 90)
			(unlocked yes)
			(layer "B.SilkS")
			(effects
				(font
					(size 0.4064 0.254)
					(thickness 0.1524)
				)
				(justify left mirror)
			)
		)
		(property "Value" ""
			(at 0 0 90)
			(layer "B.Fab")
			(effects
				(font
					(size 1.27 1.27)
				)
				(justify mirror)
			)
		)
		(duplicate_pad_numbers_are_jumpers no)
		(fp_poly
			(pts
				(xy -0.3048 -0.1016) (xy -0.3048 0.9906) (xy 0.3048 0.9906) (xy 0.3048 -0.1016)
			)
			(stroke
				(width 0)
				(type default)
			)
			(fill no)
			(layer "B.CrtYd")
		)
		(fp_line
			(start 0.3048 -0.1016)
			(end 0.3048 0.9906)
			(stroke
				(width 0.1)
				(type default)
			)
			(layer "B.Fab")
		)
		(fp_line
			(start -0.3048 -0.1016)
			(end 0.3048 -0.1016)
			(stroke
				(width 0.1)
				(type default)
			)
			(layer "B.Fab")
		)
		(fp_line
			(start 0.3048 0.9906)
			(end -0.3048 0.9906)
			(stroke
				(width 0.1)
				(type default)
			)
			(layer "B.Fab")
		)
		(fp_line
			(start -0.3048 0.9906)
			(end -0.3048 -0.1016)
			(stroke
				(width 0.1)
				(type default)
			)
			(layer "B.Fab")
		)
		(pad "1" smd rect
			(at 0 0 270)
			(size 0.508 0.508)
			(layers "B.Cu" "B.Mask" "B.Paste")
			(net "USB3_P01_TXN")
		)
		(pad "2" smd rect
			(at 0 0.889 270)
			(size 0.508 0.508)
			(layers "B.Cu" "B.Mask" "B.Paste")
			(net "USB3_P01_C_TXN")
		)
		(zone
			(layer "B.Cu")
			(hatch none 0.5)
			(connect_pads
				(clearance 0)
			)
			(min_thickness 0.25)
			(keepout
				(tracks allowed)
				(vias not_allowed)
				(pads allowed)
				(copperpour not_allowed)
				(footprints allowed)
			)
			(placement
				(enabled no)
				(sheetname "")
			)
			(fill
				(thermal_gap 0.5)
				(thermal_bridge_width 0.5)
				(island_removal_mode 0)
			)
			(polygon
				(pts
					(xy 485.51338 -61.076332) (xy 485.51338 -60.568332) (xy 485.89438 -60.568332) (xy 485.89438 -61.076332)
				)
			)
		)
		(zone
			(layer "B.Cu")
			(hatch none 0.5)
			(connect_pads
				(clearance 0)
			)
			(min_thickness 0.25)
			(keepout
				(tracks not_allowed)
				(vias allowed)
				(pads allowed)
				(copperpour not_allowed)
				(footprints allowed)
			)
			(placement
				(enabled no)
				(sheetname "")
			)
			(fill
				(thermal_gap 0.5)
				(thermal_bridge_width 0.5)
				(island_removal_mode 0)
			)
			(polygon
				(pts
					(xy 485.89438 -61.076332) (xy 485.89438 -60.568332) (xy 485.51338 -60.568332) (xy 485.51338 -61.076332)
				)
			)
		)
	)
	(footprint ""
		(layer "B.Cu")
		(at 362.715556 -121.392442 -90)
		(property "Reference" "C3M25"
			(at 0 0 90)
			(layer "B.SilkS")
			(hide yes)
			(effects
				(font
					(size 1.27 1.27)
				)
				(justify mirror)
			)
		)
		(property "Value" ""
			(at 0 0 90)
			(layer "B.Fab")
			(effects
				(font
					(size 1.27 1.27)
				)
				(justify mirror)
			)
		)
		(duplicate_pad_numbers_are_jumpers no)
		(fp_poly
			(pts
				(xy -0.3048 -0.1016) (xy -0.3048 0.9906) (xy 0.3048 0.9906) (xy 0.3048 -0.1016)
			)
			(stroke
				(width 0)
				(type default)
			)
			(fill no)
			(layer "B.CrtYd")
		)
		(fp_line
			(start -0.3048 0.9906)
			(end -0.3048 -0.1016)
			(stroke
				(width 0.1)
				(type default)
			)
			(layer "B.Fab")
		)
		(fp_line
			(start 0.3048 0.9906)
			(end -0.3048 0.9906)
			(stroke
				(width 0.1)
				(type default)
			)
			(layer "B.Fab")
		)
		(fp_line
			(start -0.3048 -0.1016)
			(end 0.3048 -0.1016)
			(stroke
				(width 0.1)
				(type default)
			)
			(layer "B.Fab")
		)
		(fp_line
			(start 0.3048 -0.1016)
			(end 0.3048 0.9906)
			(stroke
				(width 0.1)
				(type default)
			)
			(layer "B.Fab")
		)
		(pad "1" smd rect
			(at 0 0 90)
			(size 0.508 0.508)
			(layers "B.Cu" "B.Mask" "B.Paste")
			(net "P3E_CPU0_PE1_PCH_R_RXP<11>")
		)
		(pad "2" smd rect
			(at 0 0.889 90)
			(size 0.508 0.508)
			(layers "B.Cu" "B.Mask" "B.Paste")
			(net "P3E_CPU0_PE1_PCH_RXP<11>")
		)
		(zone
			(layer "B.Cu")
			(hatch none 0.5)
			(connect_pads
				(clearance 0)
			)
			(min_thickness 0.25)
			(keepout
				(tracks not_allowed)
				(vias allowed)
				(pads allowed)
				(copperpour not_allowed)
				(footprints allowed)
			)
			(placement
				(enabled no)
				(sheetname "")
			)
			(fill
				(thermal_gap 0.5)
				(thermal_bridge_width 0.5)
				(island_removal_mode 0)
			)
			(polygon
				(pts
					(xy 362.080556 -121.138442) (xy 362.080556 -121.646442) (xy 362.461556 -121.646442) (xy 362.461556 -121.138442)
				)
			)
		)
		(zone
			(layer "B.Cu")
			(hatch none 0.5)
			(connect_pads
				(clearance 0)
			)
			(min_thickness 0.25)
			(keepout
				(tracks allowed)
				(vias not_allowed)
				(pads allowed)
				(copperpour not_allowed)
				(footprints allowed)
			)
			(placement
				(enabled no)
				(sheetname "")
			)
			(fill
				(thermal_gap 0.5)
				(thermal_bridge_width 0.5)
				(island_removal_mode 0)
			)
			(polygon
				(pts
					(xy 362.461556 -121.138442) (xy 362.461556 -121.646442) (xy 362.080556 -121.646442) (xy 362.080556 -121.138442)
				)
			)
		)
	)
	(footprint ""
		(layer "B.Cu")
		(at 149.065234 -164.916866 90)
		(property "Reference" "T1D6"
			(at 0 0 90)
			(layer "B.SilkS")
			(hide yes)
			(effects
				(font
					(size 1.27 1.27)
				)
				(justify mirror)
			)
		)
		(property "Value" "*"
			(at 3.4036 -4.46405 90)
			(unlocked yes)
			(layer "B.Fab")
			(hide yes)
			(effects
				(font
					(size 0.889 0.889)
					(thickness 0.1524)
				)
				(justify mirror)
			)
		)
		(property "Device Type" "TEST-PAD-12P-1-GP-U_DISCRET-GBA"
			(at 3.4036 -5.98805 90)
			(unlocked yes)
			(layer "B.Fab")
			(hide yes)
			(effects
				(font
					(size 0.889 0.889)
					(thickness 0.1524)
				)
				(justify mirror)
			)
		)
		(duplicate_pad_numbers_are_jumpers no)
		(fp_line
			(start 2.3876 -4.826)
			(end -2.3622 -4.826)
			(stroke
				(width 0.1524)
				(type default)
			)
			(layer "B.SilkS")
		)
		(fp_line
			(start -2.3622 -4.826)
			(end -2.3622 3.4798)
			(stroke
				(width 0.1524)
				(type default)
			)
			(layer "B.SilkS")
		)
		(fp_line
			(start 2.3876 3.4798)
			(end 2.3876 -4.826)
			(stroke
				(width 0.1524)
				(type default)
			)
			(layer "B.SilkS")
		)
		(fp_line
			(start -2.3622 3.4798)
			(end 2.3876 3.4798)
			(stroke
				(width 0.1524)
				(type default)
			)
			(layer "B.SilkS")
		)
		(fp_rect
			(start 2.6416 3.7338)
			(end -2.6162 -5.08)
			(stroke
				(width 0)
				(type default)
			)
			(fill no)
			(layer "B.CrtYd")
		)
		(fp_rect
			(start 2.6416 3.7338)
			(end -2.6162 -5.08)
			(stroke
				(width 0)
				(type default)
			)
			(fill no)
			(layer "B.Fab")
		)
		(pad "1" smd circle
			(at -0.496824 -1.301496 270)
			(size 0.6604 0.6604)
			(layers "B.Cu" "B.Mask" "B.Paste")
			(net "L5_85OHM_5INCH_DN")
		)
		(pad "2" smd circle
			(at 0.503936 -1.301496 270)
			(size 0.6604 0.6604)
			(layers "B.Cu" "B.Mask" "B.Paste")
			(net "L5_85OHM_5INCH_DP")
		)
		(pad "3" smd custom
			(at 0.00889 0.370078 270)
			(size 0.74295 0.74295)
			(layers "B.Cu" "B.Mask" "B.Paste")
			(net "GND")
			(options
				(clearance outline)
				(anchor circle)
			)
			(primitives
				(gr_poly
					(pts
						(xy -2.1209 -1.4859) (xy 2.1209 -1.4859) (xy 2.1209 1.4859) (xy 1.08585 1.4859) (xy 1.08585 0.4699)
						(xy -1.08585 0.4699) (xy -1.08585 1.4859) (xy -2.1209 1.4859)
					)
					(width 0)
					(fill yes)
				)
			)
		)
		(pad "4" thru_hole circle
			(at -1.266444 -3.851656 270)
			(size 1.4478 1.4478)
			(drill 1.0414)
			(layers "*.Cu" "*.Mask")
			(remove_unused_layers no)
			(net "GND")
			(clearance 0.1524)
			(thermal_gap 0.1524)
		)
		(pad "5" thru_hole circle
			(at 1.273556 -3.851656 270)
			(size 1.4478 1.4478)
			(drill 1.0414)
			(layers "*.Cu" "*.Mask")
			(remove_unused_layers no)
			(net "GND")
			(clearance 0.1524)
			(thermal_gap 0.1524)
		)
		(pad "6" thru_hole circle
			(at -1.266444 2.498344 270)
			(size 1.4478 1.4478)
			(drill 1.0414)
			(layers "*.Cu" "*.Mask")
			(remove_unused_layers no)
			(net "GND")
			(clearance 0.1524)
			(thermal_gap 0.1524)
		)
		(pad "7" thru_hole circle
			(at 1.273556 2.498344 270)
			(size 1.4478 1.4478)
			(drill 1.0414)
			(layers "*.Cu" "*.Mask")
			(remove_unused_layers no)
			(net "GND")
			(clearance 0.1524)
			(thermal_gap 0.1524)
		)
		(pad "8" thru_hole circle
			(at -1.27 -0.4572 270)
			(size 0.7112 0.7112)
			(drill 0.4064)
			(layers "*.Cu" "*.Mask")
			(remove_unused_layers no)
			(net "GND")
			(clearance 0.1016)
			(thermal_gap 0.1016)
		)
		(pad "9" thru_hole circle
			(at -1.27 0.762 270)
			(size 0.7112 0.7112)
			(drill 0.4064)
			(layers "*.Cu" "*.Mask")
			(remove_unused_layers no)
			(net "GND")
			(clearance 0.1016)
			(thermal_gap 0.1016)
		)
		(pad "10" thru_hole circle
			(at 0.0254 0.762 270)
			(size 0.7112 0.7112)
			(drill 0.4064)
			(layers "*.Cu" "*.Mask")
			(remove_unused_layers no)
			(net "GND")
			(clearance 0.1016)
			(thermal_gap 0.1016)
		)
		(pad "11" thru_hole circle
			(at 1.27 0.762 270)
			(size 0.7112 0.7112)
			(drill 0.4064)
			(layers "*.Cu" "*.Mask")
			(remove_unused_layers no)
			(net "GND")
			(clearance 0.1016)
			(thermal_gap 0.1016)
		)
		(pad "12" thru_hole circle
			(at 1.27 -0.4572 270)
			(size 0.7112 0.7112)
			(drill 0.4064)
			(layers "*.Cu" "*.Mask")
			(remove_unused_layers no)
			(net "GND")
			(clearance 0.1016)
			(thermal_gap 0.1016)
		)
	)
	(footprint ""
		(layer "B.Cu")
		(at 24.765 -77.978)
		(property "Reference" "R9P19"
			(at 0 0 0)
			(layer "B.SilkS")
			(hide yes)
			(effects
				(font
					(size 1.27 1.27)
				)
				(justify mirror)
			)
		)
		(property "Value" ""
			(at 0 0 0)
			(layer "B.Fab")
			(effects
				(font
					(size 1.27 1.27)
				)
				(justify mirror)
			)
		)
		(duplicate_pad_numbers_are_jumpers no)
		(fp_poly
			(pts
				(xy 0.2794 -0.1016) (xy -0.2794 -0.1016) (xy -0.2794 0.9906) (xy 0.2794 0.9906)
			)
			(stroke
				(width 0)
				(type default)
			)
			(fill no)
			(layer "B.CrtYd")
		)
		(fp_line
			(start -0.2794 -0.1016)
			(end 0.2794 -0.1016)
			(stroke
				(width 0.1)
				(type default)
			)
			(layer "B.Fab")
		)
		(fp_line
			(start -0.2794 0.9906)
			(end -0.2794 -0.1016)
			(stroke
				(width 0.1)
				(type default)
			)
			(layer "B.Fab")
		)
		(fp_line
			(start 0.2794 -0.1016)
			(end 0.2794 0.9906)
			(stroke
				(width 0.1)
				(type default)
			)
			(layer "B.Fab")
		)
		(fp_line
			(start 0.2794 0.9906)
			(end -0.2794 0.9906)
			(stroke
				(width 0.1)
				(type default)
			)
			(layer "B.Fab")
		)
		(pad "1" smd rect
			(at 0 0 180)
			(size 0.508 0.508)
			(layers "B.Cu" "B.Mask" "B.Paste")
			(net "A_HSC_TIMER_R")
		)
		(pad "2" smd rect
			(at 0 0.889 180)
			(size 0.508 0.508)
			(layers "B.Cu" "B.Mask" "B.Paste")
			(net "AGND_HSC")
		)
		(zone
			(layer "B.Cu")
			(hatch none 0.5)
			(connect_pads
				(clearance 0)
			)
			(min_thickness 0.25)
			(keepout
				(tracks allowed)
				(vias not_allowed)
				(pads allowed)
				(copperpour not_allowed)
				(footprints allowed)
			)
			(placement
				(enabled no)
				(sheetname "")
			)
			(fill
				(thermal_gap 0.5)
				(thermal_bridge_width 0.5)
				(island_removal_mode 0)
			)
			(polygon
				(pts
					(xy 25.019 -77.724) (xy 24.511 -77.724) (xy 24.511 -77.343) (xy 25.019 -77.343)
				)
			)
		)
		(zone
			(layer "B.Cu")
			(hatch none 0.5)
			(connect_pads
				(clearance 0)
			)
			(min_thickness 0.25)
			(keepout
				(tracks not_allowed)
				(vias allowed)
				(pads allowed)
				(copperpour not_allowed)
				(footprints allowed)
			)
			(placement
				(enabled no)
				(sheetname "")
			)
			(fill
				(thermal_gap 0.5)
				(thermal_bridge_width 0.5)
				(island_removal_mode 0)
			)
			(polygon
				(pts
					(xy 25.019 -77.343) (xy 24.511 -77.343) (xy 24.511 -77.724) (xy 25.019 -77.724)
				)
			)
		)
	)
)
